(kicad_pcb
	(version 20241229)
	(generator "pcbnew")
	(generator_version "9.0")
	(general
		(thickness 1.6)
		(legacy_teardrops no)
	)
	(paper "A4")
	(title_block
		(title "OCuLink to PCIe adapter")
		(date "2025-06-18")
		(rev "1.0.0")
		(company "Antmicro Ltd")
		(comment 1 "www.antmicro.com")
		(comment 9 "footprints 82-85 of 159")
	)
	(layers
		(0 "F.Cu" signal)
		(4 "In1.Cu" signal)
		(6 "In2.Cu" signal)
		(2 "B.Cu" signal)
		(9 "F.Adhes" user "F.Adhesive")
		(11 "B.Adhes" user "B.Adhesive")
		(13 "F.Paste" user)
		(15 "B.Paste" user)
		(5 "F.SilkS" user "F.Silkscreen")
		(7 "B.SilkS" user "B.Silkscreen")
		(1 "F.Mask" user)
		(3 "B.Mask" user)
		(17 "Dwgs.User" user "User.Drawings")
		(19 "Cmts.User" user "User.Comments")
		(21 "Eco1.User" user "User.Eco1")
		(23 "Eco2.User" user "User.Eco2")
		(25 "Edge.Cuts" user)
		(27 "Margin" user)
		(31 "F.CrtYd" user "F.Courtyard")
		(29 "B.CrtYd" user "B.Courtyard")
		(35 "F.Fab" user)
		(33 "B.Fab" user)
	)
	(footprint "antmicro-footprints:C_Pol_EIA-B"
		(layer "F.Cu")
		(at 120.4 137.8 90)
		(property "Reference" "C3"
			(at -3.4 -0.8 180)
			(layer "F.SilkS")
			(effects
				(font
					(size 0.7 0.7)
					(thickness 0.15)
				)
				(justify left bottom)
			)
		)
		(property "Value" "C_Pol_100u_10V_KEMET-T520-B"
			(at 0 2.85 90)
			(layer "F.Fab")
			(effects
				(font
					(size 0.7 0.7)
					(thickness 0.15)
				)
				(justify left bottom)
			)
		)
		(property "Datasheet" "https://www.kemet.com/en/us/capacitors/product/T520B107M010ATE070.html"
			(at 0 0 90)
			(layer "F.Fab")
			(hide yes)
			(effects
				(font
					(size 1.27 1.27)
					(thickness 0.15)
				)
			)
		)
		(property "Description" "Tantalum Capacitors - Polymer 10V 100uF 1311 20% ESR=70mOhms"
			(at 0 0 90)
			(layer "F.Fab")
			(hide yes)
			(effects
				(font
					(size 1.27 1.27)
					(thickness 0.15)
				)
			)
		)
		(property "Val" "100u"
			(at 0 0 90)
			(unlocked yes)
			(layer "F.Fab")
			(hide yes)
			(effects
				(font
					(size 1 1)
					(thickness 0.15)
				)
			)
		)
		(property "MPN" "T520B107M010ATE070"
			(at 0 0 90)
			(unlocked yes)
			(layer "F.Fab")
			(hide yes)
			(effects
				(font
					(size 1 1)
					(thickness 0.15)
				)
			)
		)
		(property "Manufacturer" "KEMET"
			(at 0 0 90)
			(unlocked yes)
			(layer "F.Fab")
			(hide yes)
			(effects
				(font
					(size 1 1)
					(thickness 0.15)
				)
			)
		)
		(property "License" "Apache-2.0"
			(at 0 0 90)
			(unlocked yes)
			(layer "F.Fab")
			(hide yes)
			(effects
				(font
					(size 1 1)
					(thickness 0.15)
				)
			)
		)
		(property "Author" "Antmicro"
			(at 0 0 90)
			(unlocked yes)
			(layer "F.Fab")
			(hide yes)
			(effects
				(font
					(size 1 1)
					(thickness 0.15)
				)
			)
		)
		(property "Voltage" "10V"
			(at 0 0 90)
			(unlocked yes)
			(layer "F.Fab")
			(hide yes)
			(effects
				(font
					(size 1 1)
					(thickness 0.15)
				)
			)
		)
		(property "Dielectric" "template_dielectric"
			(at 0 0 90)
			(unlocked yes)
			(layer "F.Fab")
			(hide yes)
			(effects
				(font
					(size 1 1)
					(thickness 0.15)
				)
			)
		)
		(sheetname "/Power/")
		(sheetfile "power.kicad_sch")
		(attr smd)
		(fp_line
			(start -2.521 -1.676)
			(end -2.123 -1.676)
			(stroke
				(width 0.15)
				(type solid)
			)
			(layer "F.SilkS")
		)
		(fp_line
			(start -1.8 -1.6)
			(end 1.8 -1.6)
			(stroke
				(width 0.15)
				(type solid)
			)
			(layer "F.SilkS")
		)
		(fp_line
			(start -2.325 -1.475)
			(end -2.325 -1.878)
			(stroke
				(width 0.15)
				(type solid)
			)
			(layer "F.SilkS")
		)
		(fp_line
			(start 1.8 -1.3)
			(end 1.8 -1.6)
			(stroke
				(width 0.15)
				(type solid)
			)
			(layer "F.SilkS")
		)
		(fp_line
			(start -1.8 -1.3)
			(end -1.8 -1.6)
			(stroke
				(width 0.15)
				(type solid)
			)
			(layer "F.SilkS")
		)
		(fp_line
			(start 1.8 1.3)
			(end 1.8 1.6)
			(stroke
				(width 0.15)
				(type solid)
			)
			(layer "F.SilkS")
		)
		(fp_line
			(start -1.8 1.3)
			(end -1.8 1.6)
			(stroke
				(width 0.15)
				(type solid)
			)
			(layer "F.SilkS")
		)
		(fp_line
			(start 1.8 1.6)
			(end -1.8 1.6)
			(stroke
				(width 0.15)
				(type solid)
			)
			(layer "F.SilkS")
		)
		(fp_line
			(start 1.959 -1.75)
			(end -1.97 -1.75)
			(stroke
				(width 0.05)
				(type solid)
			)
			(layer "F.CrtYd")
		)
		(fp_line
			(start 1.959 -1.75)
			(end 1.959 -1.35)
			(stroke
				(width 0.05)
				(type solid)
			)
			(layer "F.CrtYd")
		)
		(fp_line
			(start -1.97 -1.75)
			(end -1.97 -1.35)
			(stroke
				(width 0.05)
				(type solid)
			)
			(layer "F.CrtYd")
		)
		(fp_line
			(start 2.399 -1.35)
			(end 1.959 -1.35)
			(stroke
				(width 0.05)
				(type solid)
			)
			(layer "F.CrtYd")
		)
		(fp_line
			(start 2.399 -1.35)
			(end 2.4 1.35)
			(stroke
				(width 0.05)
				(type solid)
			)
			(layer "F.CrtYd")
		)
		(fp_line
			(start -1.97 -1.35)
			(end -2.41 -1.35)
			(stroke
				(width 0.05)
				(type solid)
			)
			(layer "F.CrtYd")
		)
		(fp_line
			(start -2.411 -1.35)
			(end -2.41 1.35)
			(stroke
				(width 0.05)
				(type solid)
			)
			(layer "F.CrtYd")
		)
		(fp_line
			(start 2.4 1.35)
			(end 1.96 1.35)
			(stroke
				(width 0.05)
				(type solid)
			)
			(layer "F.CrtYd")
		)
		(fp_line
			(start 1.96 1.35)
			(end 1.96 1.75)
			(stroke
				(width 0.05)
				(type solid)
			)
			(layer "F.CrtYd")
		)
		(fp_line
			(start -1.97 1.35)
			(end -2.41 1.35)
			(stroke
				(width 0.05)
				(type solid)
			)
			(layer "F.CrtYd")
		)
		(fp_line
			(start -1.97 1.35)
			(end -1.97 1.75)
			(stroke
				(width 0.05)
				(type solid)
			)
			(layer "F.CrtYd")
		)
		(fp_line
			(start 1.96 1.75)
			(end -1.97 1.75)
			(stroke
				(width 0.05)
				(type solid)
			)
			(layer "F.CrtYd")
		)
		(fp_line
			(start -1.7 1.324)
			(end -1.551 1.475)
			(stroke
				(width 0.15)
				(type solid)
			)
			(layer "F.Fab")
		)
		(fp_rect
			(start -1.72 -1.5)
			(end 1.719 1.499)
			(stroke
				(width 0.15)
				(type solid)
			)
			(fill no)
			(layer "F.Fab")
		)
		(fp_text user "Author: Antmicro"
			(at -2.665 6.85 90)
			(layer "F.Fab")
			(effects
				(font
					(size 0.7 0.7)
					(thickness 0.15)
				)
				(justify left bottom)
			)
		)
		(fp_text user "License: Apache-2.0"
			(at -2.665 5.65 90)
			(layer "F.Fab")
			(effects
				(font
					(size 0.7 0.7)
					(thickness 0.15)
				)
				(justify left bottom)
			)
		)
		(fp_text user "${REFERENCE}"
			(at -0.0855 -0.089 90)
			(layer "F.Fab")
			(effects
				(font
					(size 0.7 0.7)
					(thickness 0.15)
				)
				(justify left bottom)
			)
		)
		(pad "1" smd roundrect
			(at -1.551 0 90)
			(size 1.2 2.2)
			(layers "F.Cu" "F.Mask" "F.Paste")
			(roundrect_rratio 0.1)
			(net 186 "/Power/3V3_CONV")
			(pintype "passive")
		)
		(pad "2" smd roundrect
			(at 1.55 0 90)
			(size 1.2 2.2)
			(layers "F.Cu" "F.Mask" "F.Paste")
			(roundrect_rratio 0.1)
			(net 66 "GND")
			(pintype "passive")
		)
	)
	(footprint "antmicro-footprints:C_0805_2012Metric"
		(layer "F.Cu")
		(at 119.8 117.4)
		(descr "Capacitor SMD 0805")
		(tags "capacitor SMD 0805")
		(property "Reference" "C8"
			(at -0.4 -1.2 180)
			(layer "F.SilkS")
			(effects
				(font
					(size 0.7 0.7)
					(thickness 0.15)
				)
				(justify left bottom)
			)
		)
		(property "Value" "C_10u_0805_35V"
			(at -2.055717 1.963153 0)
			(layer "F.Fab")
			(effects
				(font
					(size 0.7 0.7)
					(thickness 0.15)
				)
				(justify left bottom)
			)
		)
		(property "Datasheet" "https://www.murata.com/products/productdetail?partno=GRM21BR6YA106KE43%23"
			(at 0 0 0)
			(layer "F.Fab")
			(hide yes)
			(effects
				(font
					(size 1.27 1.27)
					(thickness 0.15)
				)
			)
		)
		(property "Description" "SMD Multilayer Ceramic Capacitor, 10 µF, 35 V, 0805 [2012 Metric], ± 10%, X5R, GRM Series"
			(at 0 0 0)
			(layer "F.Fab")
			(hide yes)
			(effects
				(font
					(size 1.27 1.27)
					(thickness 0.15)
				)
			)
		)
		(property "MPN" "GRM21BR6YA106KE43L"
			(at 0 0 0)
			(unlocked yes)
			(layer "F.Fab")
			(hide yes)
			(effects
				(font
					(size 1 1)
					(thickness 0.15)
				)
			)
		)
		(property "Manufacturer" "Murata"
			(at 0 0 0)
			(unlocked yes)
			(layer "F.Fab")
			(hide yes)
			(effects
				(font
					(size 1 1)
					(thickness 0.15)
				)
			)
		)
		(property "License" "Apache-2.0"
			(at 0 0 0)
			(unlocked yes)
			(layer "F.Fab")
			(hide yes)
			(effects
				(font
					(size 1 1)
					(thickness 0.15)
				)
			)
		)
		(property "Author" "Antmicro"
			(at 0 0 0)
			(unlocked yes)
			(layer "F.Fab")
			(hide yes)
			(effects
				(font
					(size 1 1)
					(thickness 0.15)
				)
			)
		)
		(property "Val" "10u"
			(at 0 0 0)
			(unlocked yes)
			(layer "F.Fab")
			(hide yes)
			(effects
				(font
					(size 1 1)
					(thickness 0.15)
				)
			)
		)
		(property "Voltage" "35V"
			(at 0 0 0)
			(unlocked yes)
			(layer "F.Fab")
			(hide yes)
			(effects
				(font
					(size 1 1)
					(thickness 0.15)
				)
			)
		)
		(property "Dielectric" ""
			(at 0 0 0)
			(unlocked yes)
			(layer "F.Fab")
			(hide yes)
			(effects
				(font
					(size 1 1)
					(thickness 0.15)
				)
			)
		)
		(property "Public" "False"
			(at 0 0 0)
			(unlocked yes)
			(layer "F.Fab")
			(hide yes)
			(effects
				(font
					(size 1 1)
					(thickness 0.15)
				)
			)
		)
		(sheetname "/PCIe-connector/")
		(sheetfile "pcie-connector.kicad_sch")
		(attr smd)
		(fp_line
			(start -0.3 -0.7)
			(end 0.3 -0.7)
			(stroke
				(width 0.15)
				(type solid)
			)
			(layer "F.SilkS")
		)
		(fp_line
			(start -0.3 0.7)
			(end 0.3 0.7)
			(stroke
				(width 0.15)
				(type solid)
			)
			(layer "F.SilkS")
		)
		(fp_rect
			(start 1.95 -0.9)
			(end -1.95 0.9)
			(stroke
				(width 0.05)
				(type default)
			)
			(fill no)
			(layer "F.CrtYd")
		)
		(fp_rect
			(start -0.95 -0.675)
			(end 0.95 0.675)
			(stroke
				(width 0.15)
				(type solid)
			)
			(fill no)
			(layer "F.Fab")
		)
		(fp_text user "Author: Antmicro"
			(at -1.9 5.947 0)
			(layer "F.Fab")
			(effects
				(font
					(size 0.7 0.7)
					(thickness 0.15)
				)
				(justify left bottom)
			)
		)
		(fp_text user "${REFERENCE}"
			(at 0 0 0)
			(layer "F.Fab")
			(effects
				(font
					(size 0.7 0.7)
					(thickness 0.15)
				)
				(justify left bottom)
			)
		)
		(fp_text user "License: Apache-2.0"
			(at -1.9 4.947 0)
			(layer "F.Fab")
			(effects
				(font
					(size 0.7 0.7)
					(thickness 0.15)
				)
				(justify left bottom)
			)
		)
		(pad "1" smd roundrect
			(at -1.1 0)
			(size 1.2 1.3)
			(layers "F.Cu" "F.Mask" "F.Paste")
			(roundrect_rratio 0.25)
			(net 87 "+12V")
			(pintype "passive")
		)
		(pad "2" smd roundrect
			(at 1.1 0)
			(size 1.2 1.3)
			(layers "F.Cu" "F.Mask" "F.Paste")
			(roundrect_rratio 0.25)
			(net 66 "GND")
			(pintype "passive")
		)
	)
	(footprint "antmicro-footprints:F_1206_3216Metric"
		(layer "F.Cu")
		(at 143 113 180)
		(property "Reference" "F1"
			(at 4 0.4 180)
			(layer "F.SilkS")
			(effects
				(font
					(size 0.7 0.7)
					(thickness 0.15)
				)
				(justify left top)
			)
		)
		(property "Value" "F_7A_1206"
			(at 0 2.000001 0)
			(layer "F.Fab")
			(effects
				(font
					(size 0.7 0.7)
					(thickness 0.15)
				)
				(justify right top)
			)
		)
		(property "Datasheet" "https://us.schurter.com/pdf/english/typ_UST_1206.pdf"
			(at 0 0 0)
			(layer "F.Fab")
			(hide yes)
			(effects
				(font
					(size 1.27 1.27)
					(thickness 0.15)
				)
			)
		)
		(property "Description" "7 A 32 V AC 63 V DC Fuse Board Mount (Cartridge Style Excluded) Surface Mount 1206 (3216 Metric)"
			(at 0 0 0)
			(layer "F.Fab")
			(hide yes)
			(effects
				(font
					(size 1.27 1.27)
					(thickness 0.15)
				)
			)
		)
		(property "Manufacturer" "Schurter"
			(at 0 0 180)
			(unlocked yes)
			(layer "F.Fab")
			(hide yes)
			(effects
				(font
					(size 1 1)
					(thickness 0.15)
				)
			)
		)
		(property "MPN" "3413.0326.11"
			(at 0 0 180)
			(unlocked yes)
			(layer "F.Fab")
			(hide yes)
			(effects
				(font
					(size 1 1)
					(thickness 0.15)
				)
			)
		)
		(property "Author" "Antmicro"
			(at 0 0 180)
			(unlocked yes)
			(layer "F.Fab")
			(hide yes)
			(effects
				(font
					(size 1 1)
					(thickness 0.15)
				)
			)
		)
		(property "License" "Apache-2.0"
			(at 0 0 180)
			(unlocked yes)
			(layer "F.Fab")
			(hide yes)
			(effects
				(font
					(size 1 1)
					(thickness 0.15)
				)
			)
		)
		(sheetname "/Power/")
		(sheetfile "power.kicad_sch")
		(attr smd)
		(fp_line
			(start 0.8 0.901)
			(end -0.8 0.901)
			(stroke
				(width 0.15)
				(type solid)
			)
			(layer "F.SilkS")
		)
		(fp_line
			(start 0.8 -0.899)
			(end -0.8 -0.899)
			(stroke
				(width 0.15)
				(type solid)
			)
			(layer "F.SilkS")
		)
		(fp_rect
			(start -2.325 -1.15)
			(end 2.325 1.15)
			(stroke
				(width 0.05)
				(type default)
			)
			(fill no)
			(layer "F.CrtYd")
		)
		(fp_line
			(start 1.624 0.792)
			(end -1.677 0.792)
			(stroke
				(width 0.15)
				(type solid)
			)
			(layer "F.Fab")
		)
		(fp_line
			(start 1.624 -0.861)
			(end 1.624 0.792)
			(stroke
				(width 0.15)
				(type solid)
			)
			(layer "F.Fab")
		)
		(fp_line
			(start -1.677 0.792)
			(end -1.677 -0.861)
			(stroke
				(width 0.15)
				(type solid)
			)
			(layer "F.Fab")
		)
		(fp_line
			(start -1.677 -0.861)
			(end 1.624 -0.861)
			(stroke
				(width 0.15)
				(type solid)
			)
			(layer "F.Fab")
		)
		(fp_text user "Author: Antmicro"
			(at -1.95 6.4 0)
			(layer "F.Fab")
			(effects
				(font
					(size 0.7 0.7)
					(thickness 0.15)
				)
				(justify right top)
			)
		)
		(fp_text user "${REFERENCE}"
			(at 0 0 0)
			(layer "F.Fab")
			(effects
				(font
					(size 0.7 0.7)
					(thickness 0.15)
				)
				(justify right top)
			)
		)
		(fp_text user "License: Apache-2.0"
			(at -1.95 5.2 0)
			(layer "F.Fab")
			(effects
				(font
					(size 0.7 0.7)
					(thickness 0.15)
				)
				(justify right top)
			)
		)
		(pad "1" smd roundrect
			(at -1.5 0.001 180)
			(size 1.15 1.8)
			(layers "F.Cu" "F.Mask" "F.Paste")
			(roundrect_rratio 0.25)
			(net 168 "/Power/VCC_DC_CONN_1")
			(pintype "passive")
		)
		(pad "2" smd roundrect
			(at 1.5 0.001 180)
			(size 1.15 1.8)
			(layers "F.Cu" "F.Mask" "F.Paste")
			(roundrect_rratio 0.25)
			(net 118 "/Power/Ideal-diode-1/VIN")
			(pintype "passive")
		)
	)
	(footprint "antmicro-footprints:C_0805_2012Metric"
		(layer "F.Cu")
		(at 126.9 131.05 -90)
		(descr "Capacitor SMD 0805")
		(tags "capacitor SMD 0805")
		(property "Reference" "C4"
			(at -4.35 0.4 90)
			(layer "F.SilkS")
			(effects
				(font
					(size 0.7 0.7)
					(thickness 0.15)
				)
				(justify right top)
			)
		)
		(property "Value" "C_22u_25V_0805"
			(at -2.055717 1.963153 90)
			(layer "F.Fab")
			(effects
				(font
					(size 0.7 0.7)
					(thickness 0.15)
				)
				(justify right top)
			)
		)
		(property "Datasheet" "https://product.samsungsem.com/mlcc/CL21A226MAYNNN.do"
			(at 0 0 90)
			(layer "F.Fab")
			(hide yes)
			(effects
				(font
					(size 1.27 1.27)
					(thickness 0.15)
				)
			)
		)
		(property "Description" "SMT Multilayer Ceramic Capacitor, 22uF, +/-20%, 25V, X5R, 0805 [2012 Metric]"
			(at 0 0 90)
			(layer "F.Fab")
			(hide yes)
			(effects
				(font
					(size 1.27 1.27)
					(thickness 0.15)
				)
			)
		)
		(property "MPN" "CL21A226MAYNNNE"
			(at 0 0 270)
			(unlocked yes)
			(layer "F.Fab")
			(hide yes)
			(effects
				(font
					(size 1 1)
					(thickness 0.15)
				)
			)
		)
		(property "Manufacturer" "Samsung Electro-Mechanics"
			(at 0 0 270)
			(unlocked yes)
			(layer "F.Fab")
			(hide yes)
			(effects
				(font
					(size 1 1)
					(thickness 0.15)
				)
			)
		)
		(property "License" "Apache-2.0"
			(at 0 0 270)
			(unlocked yes)
			(layer "F.Fab")
			(hide yes)
			(effects
				(font
					(size 1 1)
					(thickness 0.15)
				)
			)
		)
		(property "Author" "Antmicro"
			(at 0 0 270)
			(unlocked yes)
			(layer "F.Fab")
			(hide yes)
			(effects
				(font
					(size 1 1)
					(thickness 0.15)
				)
			)
		)
		(property "Val" "22u"
			(at 0 0 270)
			(unlocked yes)
			(layer "F.Fab")
			(hide yes)
			(effects
				(font
					(size 1 1)
					(thickness 0.15)
				)
			)
		)
		(property "Voltage" "25V"
			(at 0 0 270)
			(unlocked yes)
			(layer "F.Fab")
			(hide yes)
			(effects
				(font
					(size 1 1)
					(thickness 0.15)
				)
			)
		)
		(property "Dielectric" "X5R"
			(at 0 0 270)
			(unlocked yes)
			(layer "F.Fab")
			(hide yes)
			(effects
				(font
					(size 1 1)
					(thickness 0.15)
				)
			)
		)
		(property "Public" "False"
			(at 0 0 270)
			(unlocked yes)
			(layer "F.Fab")
			(hide yes)
			(effects
				(font
					(size 1 1)
					(thickness 0.15)
				)
			)
		)
		(sheetname "/Power/")
		(sheetfile "power.kicad_sch")
		(attr smd)
		(fp_line
			(start -0.3 0.7)
			(end 0.3 0.7)
			(stroke
				(width 0.15)
				(type solid)
			)
			(layer "F.SilkS")
		)
		(fp_line
			(start -0.3 -0.7)
			(end 0.3 -0.7)
			(stroke
				(width 0.15)
				(type solid)
			)
			(layer "F.SilkS")
		)
		(fp_rect
			(start 1.95 -0.9)
			(end -1.95 0.9)
			(stroke
				(width 0.05)
				(type default)
			)
			(fill no)
			(layer "F.CrtYd")
		)
		(fp_rect
			(start -0.95 -0.675)
			(end 0.95 0.675)
			(stroke
				(width 0.15)
				(type solid)
			)
			(fill no)
			(layer "F.Fab")
		)
		(fp_text user "Author: Antmicro"
			(at -1.9 5.947 90)
			(layer "F.Fab")
			(effects
				(font
					(size 0.7 0.7)
					(thickness 0.15)
				)
				(justify right top)
			)
		)
		(fp_text user "License: Apache-2.0"
			(at -1.9 4.947 90)
			(layer "F.Fab")
			(effects
				(font
					(size 0.7 0.7)
					(thickness 0.15)
				)
				(justify right top)
			)
		)
		(fp_text user "${REFERENCE}"
			(at 0 0 90)
			(layer "F.Fab")
			(effects
				(font
					(size 0.7 0.7)
					(thickness 0.15)
				)
				(justify right top)
			)
		)
		(pad "1" smd roundrect
			(at -1.1 0 270)
			(size 1.2 1.3)
			(layers "F.Cu" "F.Mask" "F.Paste")
			(roundrect_rratio 0.25)
			(net 66 "GND")
			(pintype "passive")
		)
		(pad "2" smd roundrect
			(at 1.1 0 270)
			(size 1.2 1.3)
			(layers "F.Cu" "F.Mask" "F.Paste")
			(roundrect_rratio 0.25)
			(net 87 "+12V")
			(pintype "passive")
		)
	)
)
